# S9S_MB_2U (Grand Teton) — schematic netlist excerpt (pin names and nets, part order shuffled) for the footprints in the layout excerpt that follows; sources: Cadence DE-HDL packaged netlist, KiCad conversion of 03242023_DA0F0TMBIJ0_F0T_Motherboard_J_brd_V01_OCP.brd

C1821  Q_CAP  0.1UF 25V 10% X7R  pkg 0402  page 161 : A = P3V3_AUX ; B = GND
R2426  Q_RES  100 1% EMPTY  pkg 0402LF  page 191 : A = E1S_0_PERST1_CLKREQ_N ; B = GND

(kicad_pcb
	(version 20260206)
	(generator "pcbnew")
	(generator_version "10.0")
	(general
		(thickness 1.6)
		(legacy_teardrops no)
	)
	(paper "A4")
	(title_block
		(title "03242023_DA0F0TMBIJ0_F0T_Motherboard_J_brd_V01_OCP.brd")
		(comment 1 "Grand Teton / footprints 444-445 of 6105")
	)
	(layers
		(0 "F.Cu" signal "TOP")
		(4 "In1.Cu" signal "GND")
		(6 "In2.Cu" signal "IN1")
		(8 "In3.Cu" signal "GND1")
		(10 "In4.Cu" signal "IN2")
		(12 "In5.Cu" signal "GND2")
		(14 "In6.Cu" signal "IN3")
		(16 "In7.Cu" signal "GND3")
		(18 "In8.Cu" signal "VCC")
		(20 "In9.Cu" signal "VCC1")
		(22 "In10.Cu" signal "GND4")
		(24 "In11.Cu" signal "IN4")
		(26 "In12.Cu" signal "GND5")
		(28 "In13.Cu" signal "IN5")
		(30 "In14.Cu" signal "GND6")
		(32 "In15.Cu" signal "IN6")
		(34 "In16.Cu" signal "GND7")
		(2 "B.Cu" signal "BOTTOM")
		(9 "F.Adhes" user "F.Adhesive")
		(11 "B.Adhes" user "B.Adhesive")
		(13 "F.Paste" user "Package Geometry/Pastemask Top")
		(15 "B.Paste" user "Package Geometry/Pastemask Bottom")
		(5 "F.SilkS" user "Ref Des/Silkscreen Top")
		(7 "B.SilkS" user "Ref Des/Silkscreen Bottom")
		(1 "F.Mask" user "Board Geometry/Soldermask Top")
		(3 "B.Mask" user "Board Geometry/Soldermask Bottom")
		(17 "Dwgs.User" user "User.Drawings")
		(19 "Cmts.User" user "User.Comments")
		(21 "Eco1.User" user "User.Eco1")
		(23 "Eco2.User" user "User.Eco2")
		(25 "Edge.Cuts" user "Board Geometry/Outline")
		(27 "Margin" user)
		(31 "F.CrtYd" user "Package Geometry/Place Bound Top")
		(29 "B.CrtYd" user "Package Geometry/Place Bound Bottom")
		(35 "F.Fab" user "Ref Des/Assembly Top")
		(33 "B.Fab" user "Ref Des/Assembly Bottom")
	)
	(footprint ""
		(layer "F.Cu")
		(at 104.104186 -40.935148)
		(property "Reference" "C1821"
			(at 0 0 0)
			(layer "F.SilkS")
			(hide yes)
			(effects
				(font
					(size 1.27 1.27)
				)
			)
		)
		(property "Value" ""
			(at 0 0 0)
			(layer "F.Fab")
			(effects
				(font
					(size 1.27 1.27)
				)
			)
		)
		(duplicate_pad_numbers_are_jumpers no)
		(fp_line
			(start -0.7874 -0.4064)
			(end 0.7874 -0.4064)
			(stroke
				(width 0.1524)
				(type default)
			)
			(layer "F.SilkS")
		)
		(fp_line
			(start -0.7874 0.4064)
			(end -0.7874 -0.4064)
			(stroke
				(width 0.1524)
				(type default)
			)
			(layer "F.SilkS")
		)
		(fp_line
			(start 0.7874 -0.4064)
			(end 0.7874 0.4064)
			(stroke
				(width 0.1524)
				(type default)
			)
			(layer "F.SilkS")
		)
		(fp_line
			(start 0.7874 0.4064)
			(end -0.7874 0.4064)
			(stroke
				(width 0.1524)
				(type default)
			)
			(layer "F.SilkS")
		)
		(fp_line
			(start -0.67945 -0.305054)
			(end -0.12065 -0.305054)
			(stroke
				(width 0.1)
				(type default)
			)
			(layer "F.Fab")
		)
		(fp_line
			(start -0.67945 0.3048)
			(end -0.67945 -0.305054)
			(stroke
				(width 0.1)
				(type default)
			)
			(layer "F.Fab")
		)
		(fp_line
			(start -0.12065 -0.305054)
			(end -0.12065 -0.2794)
			(stroke
				(width 0.1)
				(type default)
			)
			(layer "F.Fab")
		)
		(fp_line
			(start -0.12065 -0.2794)
			(end 0.12065 -0.2794)
			(stroke
				(width 0.1)
				(type default)
			)
			(layer "F.Fab")
		)
		(fp_line
			(start -0.12065 0.2794)
			(end -0.12065 0.3048)
			(stroke
				(width 0.1)
				(type default)
			)
			(layer "F.Fab")
		)
		(fp_line
			(start -0.12065 0.3048)
			(end -0.67945 0.3048)
			(stroke
				(width 0.1)
				(type default)
			)
			(layer "F.Fab")
		)
		(fp_line
			(start 0.120396 0.2794)
			(end -0.12065 0.2794)
			(stroke
				(width 0.1)
				(type default)
			)
			(layer "F.Fab")
		)
		(fp_line
			(start 0.120396 0.3048)
			(end 0.120396 0.2794)
			(stroke
				(width 0.1)
				(type default)
			)
			(layer "F.Fab")
		)
		(fp_line
			(start 0.12065 -0.3048)
			(end 0.67945 -0.3048)
			(stroke
				(width 0.1)
				(type default)
			)
			(layer "F.Fab")
		)
		(fp_line
			(start 0.12065 -0.2794)
			(end 0.12065 -0.3048)
			(stroke
				(width 0.1)
				(type default)
			)
			(layer "F.Fab")
		)
		(fp_line
			(start 0.67945 -0.3048)
			(end 0.67945 0.3048)
			(stroke
				(width 0.1)
				(type default)
			)
			(layer "F.Fab")
		)
		(fp_line
			(start 0.67945 0.3048)
			(end 0.120396 0.3048)
			(stroke
				(width 0.1)
				(type default)
			)
			(layer "F.Fab")
		)
		(pad "1" smd circle
			(at -0.40005 0)
			(size 0 0)
			(layers "F.Cu" "F.Mask" "F.Paste")
			(net "P3V3_AUX")
		)
		(pad "2" smd circle
			(at 0.40005 0)
			(size 0 0)
			(layers "F.Cu" "F.Mask" "F.Paste")
			(net "GND")
		)
	)
	(footprint ""
		(layer "F.Cu")
		(at 224.21215 -48.78197 180)
		(property "Reference" "R2426"
			(at 0 0 180)
			(layer "F.SilkS")
			(hide yes)
			(effects
				(font
					(size 1.27 1.27)
				)
			)
		)
		(property "Value" ""
			(at 0 0 180)
			(layer "F.Fab")
			(effects
				(font
					(size 1.27 1.27)
				)
			)
		)
		(duplicate_pad_numbers_are_jumpers no)
		(fp_line
			(start 0.7874 0.4064)
			(end -0.7874 0.4064)
			(stroke
				(width 0.1524)
				(type default)
			)
			(layer "F.SilkS")
		)
		(fp_line
			(start 0.7874 -0.4064)
			(end 0.7874 0.4064)
			(stroke
				(width 0.1524)
				(type default)
			)
			(layer "F.SilkS")
		)
		(fp_line
			(start -0.7874 0.4064)
			(end -0.7874 -0.4064)
			(stroke
				(width 0.1524)
				(type default)
			)
			(layer "F.SilkS")
		)
		(fp_line
			(start -0.7874 -0.4064)
			(end 0.7874 -0.4064)
			(stroke
				(width 0.1524)
				(type default)
			)
			(layer "F.SilkS")
		)
		(fp_line
			(start 0.67945 0.3048)
			(end 0.120396 0.3048)
			(stroke
				(width 0.1)
				(type default)
			)
			(layer "F.Fab")
		)
		(fp_line
			(start 0.67945 -0.3048)
			(end 0.67945 0.3048)
			(stroke
				(width 0.1)
				(type default)
			)
			(layer "F.Fab")
		)
		(fp_line
			(start 0.12065 -0.2794)
			(end 0.12065 -0.3048)
			(stroke
				(width 0.1)
				(type default)
			)
			(layer "F.Fab")
		)
		(fp_line
			(start 0.12065 -0.3048)
			(end 0.67945 -0.3048)
			(stroke
				(width 0.1)
				(type default)
			)
			(layer "F.Fab")
		)
		(fp_line
			(start 0.120396 0.3048)
			(end 0.120396 0.2794)
			(stroke
				(width 0.1)
				(type default)
			)
			(layer "F.Fab")
		)
		(fp_line
			(start 0.120396 0.2794)
			(end -0.12065 0.2794)
			(stroke
				(width 0.1)
				(type default)
			)
			(layer "F.Fab")
		)
		(fp_line
			(start -0.12065 0.3048)
			(end -0.67945 0.3048)
			(stroke
				(width 0.1)
				(type default)
			)
			(layer "F.Fab")
		)
		(fp_line
			(start -0.12065 0.2794)
			(end -0.12065 0.3048)
			(stroke
				(width 0.1)
				(type default)
			)
			(layer "F.Fab")
		)
		(fp_line
			(start -0.12065 -0.2794)
			(end 0.12065 -0.2794)
			(stroke
				(width 0.1)
				(type default)
			)
			(layer "F.Fab")
		)
		(fp_line
			(start -0.12065 -0.305054)
			(end -0.12065 -0.2794)
			(stroke
				(width 0.1)
				(type default)
			)
			(layer "F.Fab")
		)
		(fp_line
			(start -0.67945 0.3048)
			(end -0.67945 -0.305054)
			(stroke
				(width 0.1)
				(type default)
			)
			(layer "F.Fab")
		)
		(fp_line
			(start -0.67945 -0.305054)
			(end -0.12065 -0.305054)
			(stroke
				(width 0.1)
				(type default)
			)
			(layer "F.Fab")
		)
		(pad "1" smd circle
			(at -0.40005 0 180)
			(size 0 0)
			(layers "F.Cu" "F.Mask" "F.Paste")
			(net "E1S_0_PERST1_CLKREQ_N")
		)
		(pad "2" smd circle
			(at 0.40005 0 180)
			(size 0 0)
			(layers "F.Cu" "F.Mask" "F.Paste")
			(net "GND")
		)
	)
)
